(kicad_pcb
	(version 20260206)
	(generator "pcbnew")
	(generator_version "10.0")
	(general
		(thickness 1.6)
		(legacy_teardrops no)
	)
	(paper "A4")
	(title_block
		(title "04192023_DAF0TMB3IC0_F0TG_MB_C_brd_V02_OCP.brd")
		(comment 1 "Grand Teton / footprint 2783 of 8354 (U26), pads 4342-4451 of 6102")
	)
	(layers
		(0 "F.Cu" signal "TOP")
		(4 "In1.Cu" signal "GND")
		(6 "In2.Cu" signal "IN1")
		(8 "In3.Cu" signal "GND1")
		(10 "In4.Cu" signal "IN2")
		(12 "In5.Cu" signal "GND2")
		(14 "In6.Cu" signal "IN3")
		(16 "In7.Cu" signal "GND3")
		(18 "In8.Cu" signal "VCC")
		(20 "In9.Cu" signal "VCC1")
		(22 "In10.Cu" signal "GND4")
		(24 "In11.Cu" signal "IN4")
		(26 "In12.Cu" signal "GND5")
		(28 "In13.Cu" signal "IN5")
		(30 "In14.Cu" signal "GND6")
		(32 "In15.Cu" signal "IN6")
		(34 "In16.Cu" signal "GND7")
		(2 "B.Cu" signal "BOTTOM")
		(9 "F.Adhes" user "F.Adhesive")
		(11 "B.Adhes" user "B.Adhesive")
		(13 "F.Paste" user "Package Geometry/Pastemask Top")
		(15 "B.Paste" user "Package Geometry/Pastemask Bottom")
		(5 "F.SilkS" user "Ref Des/Silkscreen Top")
		(7 "B.SilkS" user "Ref Des/Silkscreen Bottom")
		(1 "F.Mask" user "Board Geometry/Soldermask Top")
		(3 "B.Mask" user "Board Geometry/Soldermask Bottom")
		(17 "Dwgs.User" user "User.Drawings")
		(19 "Cmts.User" user "User.Comments")
		(21 "Eco1.User" user "User.Eco1")
		(23 "Eco2.User" user "User.Eco2")
		(25 "Edge.Cuts" user "Board Geometry/Outline")
		(27 "Margin" user)
		(31 "F.CrtYd" user "Package Geometry/Place Bound Top")
		(29 "B.CrtYd" user "Package Geometry/Place Bound Bottom")
		(35 "F.Fab" user "Ref Des/Assembly Top")
		(33 "B.Fab" user "Ref Des/Assembly Bottom")
	)
	(footprint ""
		(layer "F.Cu")
		(at 111.927894 -258.880356 180)
		(property "Reference" "U26"
			(at -45.05579 -61.794136 0)
			(unlocked yes)
			(layer "F.SilkS")
			(effects
				(font
					(size 0.7874 0.5842)
					(thickness 0.1524)
				)
			)
		)
		(property "Value" ""
			(at 0 0 180)
			(layer "F.Fab")
			(effects
				(font
					(size 1.27 1.27)
				)
			)
		)
		(duplicate_pad_numbers_are_jumpers no)
		(pad "DA22" smd circle
			(at -14.720062 30.329886 180)
			(size 0.450088 0.450088)
			(layers "F.Cu" "F.Mask" "F.Paste")
			(net "GND")
		)
		(pad "DA23" smd circle
			(at -13.780008 30.329886 180)
			(size 0.450088 0.450088)
			(layers "F.Cu" "F.Mask" "F.Paste")
			(net "P5E_CPU1_P3_RX_DP<14>")
		)
		(pad "DA24" smd circle
			(at -12.839954 30.329886 180)
			(size 0.450088 0.450088)
			(layers "F.Cu" "F.Mask" "F.Paste")
			(net "P5E_CPU1_P3_RX_DN<14>")
		)
		(pad "DA25" smd circle
			(at -11.8999 30.329886 180)
			(size 0.450088 0.450088)
			(layers "F.Cu" "F.Mask" "F.Paste")
			(net "GND")
		)
		(pad "DA26" smd circle
			(at -10.9601 30.329886 180)
			(size 0.450088 0.450088)
			(layers "F.Cu" "F.Mask" "F.Paste")
			(net "P5E_CPU1_P3_RX_DP<11>")
		)
		(pad "DA27" smd circle
			(at -10.020046 30.329886 180)
			(size 0.450088 0.450088)
			(layers "F.Cu" "F.Mask" "F.Paste")
			(net "P5E_CPU1_P3_RX_DN<11>")
		)
		(pad "DA28" smd circle
			(at -9.079992 30.329886 180)
			(size 0.450088 0.450088)
			(layers "F.Cu" "F.Mask" "F.Paste")
			(net "GND")
		)
		(pad "DA29" smd circle
			(at -8.139938 30.329886 180)
			(size 0.450088 0.450088)
			(layers "F.Cu" "F.Mask" "F.Paste")
			(net "P5E_CPU1_P3_RX_DP<8>")
		)
		(pad "DA30" smd circle
			(at -7.199884 30.329886 180)
			(size 0.450088 0.450088)
			(layers "F.Cu" "F.Mask" "F.Paste")
			(net "P5E_CPU1_P3_RX_DN<8>")
		)
		(pad "DA31" smd circle
			(at -6.260084 30.329886 180)
			(size 0.450088 0.450088)
			(layers "F.Cu" "F.Mask" "F.Paste")
			(net "GND")
		)
		(pad "DA32" smd circle
			(at -5.32003 30.329886 180)
			(size 0.450088 0.450088)
			(layers "F.Cu" "F.Mask" "F.Paste")
			(net "P5E_CPU1_P3_RX_DP<5>")
		)
		(pad "DA33" smd circle
			(at -4.379976 30.329886 180)
			(size 0.450088 0.450088)
			(layers "F.Cu" "F.Mask" "F.Paste")
			(net "P5E_CPU1_P3_RX_DN<5>")
		)
		(pad "DA34" smd circle
			(at -3.439922 30.329886 180)
			(size 0.450088 0.450088)
			(layers "F.Cu" "F.Mask" "F.Paste")
			(net "GND")
		)
		(pad "DA35" smd circle
			(at -2.500122 30.329886 180)
			(size 0.450088 0.450088)
			(layers "F.Cu" "F.Mask" "F.Paste")
			(net "PVDDCR_CPU1_P1")
		)
		(pad "DA36" smd circle
			(at -1.560068 30.329886 180)
			(size 0.450088 0.450088)
			(layers "F.Cu" "F.Mask" "F.Paste")
			(net "PVDDCR_CPU1_P1")
		)
		(pad "DA40" smd circle
			(at 1.260094 30.329886 180)
			(size 0.450088 0.450088)
			(layers "F.Cu" "F.Mask" "F.Paste")
			(net "PVDDCR_CPU1_P1")
		)
		(pad "DA41" smd circle
			(at 2.199894 30.329886 180)
			(size 0.450088 0.450088)
			(layers "F.Cu" "F.Mask" "F.Paste")
			(net "PVDDCR_CPU1_P1")
		)
		(pad "DA42" smd circle
			(at 3.139948 30.329886 180)
			(size 0.450088 0.450088)
			(layers "F.Cu" "F.Mask" "F.Paste")
			(net "GND")
		)
		(pad "DA43" smd circle
			(at 4.080002 30.329886 180)
			(size 0.450088 0.450088)
			(layers "F.Cu" "F.Mask" "F.Paste")
			(net "P5E_CPU1_P1_TX_DN<10>")
		)
		(pad "DA44" smd circle
			(at 5.020056 30.329886 180)
			(size 0.450088 0.450088)
			(layers "F.Cu" "F.Mask" "F.Paste")
			(net "P5E_CPU1_P1_TX_DP<10>")
		)
		(pad "DA45" smd circle
			(at 5.96011 30.329886 180)
			(size 0.450088 0.450088)
			(layers "F.Cu" "F.Mask" "F.Paste")
			(net "GND")
		)
		(pad "DA46" smd circle
			(at 6.89991 30.329886 180)
			(size 0.450088 0.450088)
			(layers "F.Cu" "F.Mask" "F.Paste")
			(net "P5E_CPU1_P1_TX_DN<7>")
		)
		(pad "DA47" smd circle
			(at 7.839964 30.329886 180)
			(size 0.450088 0.450088)
			(layers "F.Cu" "F.Mask" "F.Paste")
			(net "P5E_CPU1_P1_TX_DP<7>")
		)
		(pad "DA48" smd circle
			(at 8.780018 30.329886 180)
			(size 0.450088 0.450088)
			(layers "F.Cu" "F.Mask" "F.Paste")
			(net "GND")
		)
		(pad "DA49" smd circle
			(at 9.720072 30.329886 180)
			(size 0.450088 0.450088)
			(layers "F.Cu" "F.Mask" "F.Paste")
			(net "P5E_CPU1_P1_TX_DN<4>")
		)
		(pad "DA50" smd circle
			(at 10.659872 30.329886 180)
			(size 0.450088 0.450088)
			(layers "F.Cu" "F.Mask" "F.Paste")
			(net "P5E_CPU1_P1_TX_DP<4>")
		)
		(pad "DA51" smd circle
			(at 11.599926 30.329886 180)
			(size 0.450088 0.450088)
			(layers "F.Cu" "F.Mask" "F.Paste")
			(net "GND")
		)
		(pad "DA52" smd circle
			(at 12.53998 30.329886 180)
			(size 0.450088 0.450088)
			(layers "F.Cu" "F.Mask" "F.Paste")
			(net "P5E_CPU1_P1_TX_DN<1>")
		)
		(pad "DA53" smd circle
			(at 13.480034 30.329886 180)
			(size 0.450088 0.450088)
			(layers "F.Cu" "F.Mask" "F.Paste")
			(net "P5E_CPU1_P1_TX_DP<1>")
		)
		(pad "DA54" smd circle
			(at 14.420088 30.329886 180)
			(size 0.450088 0.450088)
			(layers "F.Cu" "F.Mask" "F.Paste")
			(net "GND")
		)
		(pad "DA55" smd circle
			(at 15.359888 30.329886 180)
			(size 0.450088 0.450088)
			(layers "F.Cu" "F.Mask" "F.Paste")
			(net "M_C_CPU1_SB_DQ<25>")
		)
		(pad "DA56" smd circle
			(at 16.299942 30.329886 180)
			(size 0.450088 0.450088)
			(layers "F.Cu" "F.Mask" "F.Paste")
			(net "GND")
		)
		(pad "DA57" smd circle
			(at 17.239996 30.329886 180)
			(size 0.450088 0.450088)
			(layers "F.Cu" "F.Mask" "F.Paste")
			(net "M_C_CPU1_SB_DQ<26>")
		)
		(pad "DA58" smd circle
			(at 18.18005 30.329886 180)
			(size 0.450088 0.450088)
			(layers "F.Cu" "F.Mask" "F.Paste")
			(net "GND")
		)
		(pad "DA59" smd circle
			(at 19.120104 30.329886 180)
			(size 0.450088 0.450088)
			(layers "F.Cu" "F.Mask" "F.Paste")
			(net "M_D_CPU1_SB_DQ<25>")
		)
		(pad "DA60" smd circle
			(at 20.059904 30.329886 180)
			(size 0.450088 0.450088)
			(layers "F.Cu" "F.Mask" "F.Paste")
			(net "M_D_CPU1_SB_DQ<26>")
		)
		(pad "DA61" smd circle
			(at 20.999958 30.329886 180)
			(size 0.450088 0.450088)
			(layers "F.Cu" "F.Mask" "F.Paste")
			(net "GND")
		)
		(pad "DA62" smd circle
			(at 21.940012 30.329886 180)
			(size 0.450088 0.450088)
			(layers "F.Cu" "F.Mask" "F.Paste")
			(net "M_B_CPU1_SB_DQ<25>")
		)
		(pad "DA63" smd circle
			(at 22.880066 30.329886 180)
			(size 0.450088 0.450088)
			(layers "F.Cu" "F.Mask" "F.Paste")
			(net "GND")
		)
		(pad "DA64" smd circle
			(at 23.82012 30.329886 180)
			(size 0.450088 0.450088)
			(layers "F.Cu" "F.Mask" "F.Paste")
			(net "M_B_CPU1_SB_DQ<26>")
		)
		(pad "DA65" smd circle
			(at 24.75992 30.329886 180)
			(size 0.450088 0.450088)
			(layers "F.Cu" "F.Mask" "F.Paste")
			(net "GND")
		)
		(pad "DA66" smd circle
			(at 25.699974 30.329886 180)
			(size 0.450088 0.450088)
			(layers "F.Cu" "F.Mask" "F.Paste")
			(net "M_F_CPU1_SB_DQ<25>")
		)
		(pad "DA67" smd circle
			(at 26.640028 30.329886 180)
			(size 0.450088 0.450088)
			(layers "F.Cu" "F.Mask" "F.Paste")
			(net "M_F_CPU1_SB_DQ<26>")
		)
		(pad "DA68" smd circle
			(at 27.580082 30.329886 180)
			(size 0.450088 0.450088)
			(layers "F.Cu" "F.Mask" "F.Paste")
			(net "GND")
		)
		(pad "DA69" smd circle
			(at 28.519882 30.329886 180)
			(size 0.450088 0.450088)
			(layers "F.Cu" "F.Mask" "F.Paste")
			(net "M_E_CPU1_SB_DQ<25>")
		)
		(pad "DA70" smd circle
			(at 29.459936 30.329886 180)
			(size 0.450088 0.450088)
			(layers "F.Cu" "F.Mask" "F.Paste")
			(net "GND")
		)
		(pad "DA71" smd circle
			(at 30.39999 30.329886 180)
			(size 0.450088 0.450088)
			(layers "F.Cu" "F.Mask" "F.Paste")
			(net "M_E_CPU1_SB_DQ<26>")
		)
		(pad "DA72" smd circle
			(at 31.340044 30.329886 180)
			(size 0.450088 0.450088)
			(layers "F.Cu" "F.Mask" "F.Paste")
			(net "GND")
		)
		(pad "DA73" smd circle
			(at 32.280098 30.329886 180)
			(size 0.450088 0.450088)
			(layers "F.Cu" "F.Mask" "F.Paste")
			(net "M_A_CPU1_SB_DQ<25>")
		)
		(pad "DA74" smd circle
			(at 33.219898 30.329886 180)
			(size 0.450088 0.450088)
			(layers "F.Cu" "F.Mask" "F.Paste")
			(net "M_A_CPU1_SB_DQ<26>")
		)
		(pad "DA75" smd circle
			(at 34.159952 30.329886 180)
			(size 0.450088 0.450088)
			(layers "F.Cu" "F.Mask" "F.Paste")
			(net "GND")
		)
		(pad "DB2" smd circle
			(at -33.990026 31.139892 180)
			(size 0.450088 0.450088)
			(layers "F.Cu" "F.Mask" "F.Paste")
			(net "M_G_CPU1_SB_DQS_DP<3>")
		)
		(pad "DB3" smd circle
			(at -33.049972 31.139892 180)
			(size 0.450088 0.450088)
			(layers "F.Cu" "F.Mask" "F.Paste")
			(net "GND")
		)
		(pad "DB4" smd circle
			(at -32.109918 31.139892 180)
			(size 0.450088 0.450088)
			(layers "F.Cu" "F.Mask" "F.Paste")
			(net "M_G_CPU1_SB_DQ<27>")
		)
		(pad "DB5" smd circle
			(at -31.170118 31.139892 180)
			(size 0.450088 0.450088)
			(layers "F.Cu" "F.Mask" "F.Paste")
			(net "PVDD11_S3_P1")
		)
		(pad "DB6" smd circle
			(at -30.230064 31.139892 180)
			(size 0.450088 0.450088)
			(layers "F.Cu" "F.Mask" "F.Paste")
			(net "M_K_CPU1_SB_DQS_DP<3>")
		)
		(pad "DB7" smd circle
			(at -29.29001 31.139892 180)
			(size 0.450088 0.450088)
			(layers "F.Cu" "F.Mask" "F.Paste")
			(net "M_K_CPU1_SB_DQ<27>")
		)
		(pad "DB8" smd circle
			(at -28.349956 31.139892 180)
			(size 0.450088 0.450088)
			(layers "F.Cu" "F.Mask" "F.Paste")
			(net "GND")
		)
		(pad "DB9" smd circle
			(at -27.409902 31.139892 180)
			(size 0.450088 0.450088)
			(layers "F.Cu" "F.Mask" "F.Paste")
			(net "M_L_CPU1_SB_DQS_DP<3>")
		)
		(pad "DB10" smd circle
			(at -26.470102 31.139892 180)
			(size 0.450088 0.450088)
			(layers "F.Cu" "F.Mask" "F.Paste")
			(net "GND")
		)
		(pad "DB11" smd circle
			(at -25.530048 31.139892 180)
			(size 0.450088 0.450088)
			(layers "F.Cu" "F.Mask" "F.Paste")
			(net "M_L_CPU1_SB_DQ<27>")
		)
		(pad "DB12" smd circle
			(at -24.589994 31.139892 180)
			(size 0.450088 0.450088)
			(layers "F.Cu" "F.Mask" "F.Paste")
			(net "PVDD11_S3_P1")
		)
		(pad "DB13" smd circle
			(at -23.64994 31.139892 180)
			(size 0.450088 0.450088)
			(layers "F.Cu" "F.Mask" "F.Paste")
			(net "M_H_CPU1_SB_DQS_DP<3>")
		)
		(pad "DB14" smd circle
			(at -22.709886 31.139892 180)
			(size 0.450088 0.450088)
			(layers "F.Cu" "F.Mask" "F.Paste")
			(net "M_H_CPU1_SB_DQ<27>")
		)
		(pad "DB15" smd circle
			(at -21.770086 31.139892 180)
			(size 0.450088 0.450088)
			(layers "F.Cu" "F.Mask" "F.Paste")
			(net "GND")
		)
		(pad "DB16" smd circle
			(at -20.830032 31.139892 180)
			(size 0.450088 0.450088)
			(layers "F.Cu" "F.Mask" "F.Paste")
			(net "M_J_CPU1_SB_DQS_DP<3>")
		)
		(pad "DB17" smd circle
			(at -19.889978 31.139892 180)
			(size 0.450088 0.450088)
			(layers "F.Cu" "F.Mask" "F.Paste")
			(net "GND")
		)
		(pad "DB18" smd circle
			(at -18.949924 31.139892 180)
			(size 0.450088 0.450088)
			(layers "F.Cu" "F.Mask" "F.Paste")
			(net "M_J_CPU1_SB_DQ<27>")
		)
		(pad "DB19" smd circle
			(at -18.010124 31.139892 180)
			(size 0.450088 0.450088)
			(layers "F.Cu" "F.Mask" "F.Paste")
			(net "PVDD11_S3_P1")
		)
		(pad "DB20" smd circle
			(at -17.07007 31.139892 180)
			(size 0.450088 0.450088)
			(layers "F.Cu" "F.Mask" "F.Paste")
			(net "M_I_CPU1_SB_DQS_DP<3>")
		)
		(pad "DB21" smd circle
			(at -16.130016 31.139892 180)
			(size 0.450088 0.450088)
			(layers "F.Cu" "F.Mask" "F.Paste")
			(net "M_I_CPU1_SB_DQ<27>")
		)
		(pad "DB22" smd circle
			(at -15.189962 31.139892 180)
			(size 0.450088 0.450088)
			(layers "F.Cu" "F.Mask" "F.Paste")
			(net "GND")
		)
		(pad "DB23" smd circle
			(at -14.249908 31.139892 180)
			(size 0.450088 0.450088)
			(layers "F.Cu" "F.Mask" "F.Paste")
			(net "PVDDCR_CPU1_P1")
		)
		(pad "DB24" smd circle
			(at -13.310108 31.139892 180)
			(size 0.450088 0.450088)
			(layers "F.Cu" "F.Mask" "F.Paste")
			(net "PVDDCR_CPU1_P1")
		)
		(pad "DB25" smd circle
			(at -12.370054 31.139892 180)
			(size 0.450088 0.450088)
			(layers "F.Cu" "F.Mask" "F.Paste")
			(net "GND")
		)
		(pad "DB26" smd circle
			(at -11.43 31.139892 180)
			(size 0.450088 0.450088)
			(layers "F.Cu" "F.Mask" "F.Paste")
			(net "PVDDCR_CPU1_P1")
		)
		(pad "DB27" smd circle
			(at -10.489946 31.139892 180)
			(size 0.450088 0.450088)
			(layers "F.Cu" "F.Mask" "F.Paste")
			(net "PVDDCR_CPU1_P1")
		)
		(pad "DB28" smd circle
			(at -9.549892 31.139892 180)
			(size 0.450088 0.450088)
			(layers "F.Cu" "F.Mask" "F.Paste")
			(net "GND")
		)
		(pad "DB29" smd circle
			(at -8.610092 31.139892 180)
			(size 0.450088 0.450088)
			(layers "F.Cu" "F.Mask" "F.Paste")
			(net "PVDDCR_CPU1_P1")
		)
		(pad "DB30" smd circle
			(at -7.670038 31.139892 180)
			(size 0.450088 0.450088)
			(layers "F.Cu" "F.Mask" "F.Paste")
			(net "PVDDCR_CPU1_P1")
		)
		(pad "DB31" smd circle
			(at -6.729984 31.139892 180)
			(size 0.450088 0.450088)
			(layers "F.Cu" "F.Mask" "F.Paste")
			(net "GND")
		)
		(pad "DB32" smd circle
			(at -5.78993 31.139892 180)
			(size 0.450088 0.450088)
			(layers "F.Cu" "F.Mask" "F.Paste")
			(net "PVDDCR_CPU1_P1")
		)
		(pad "DB33" smd circle
			(at -4.849876 31.139892 180)
			(size 0.450088 0.450088)
			(layers "F.Cu" "F.Mask" "F.Paste")
			(net "PVDDCR_CPU1_P1")
		)
		(pad "DB34" smd circle
			(at -3.910076 31.139892 180)
			(size 0.450088 0.450088)
			(layers "F.Cu" "F.Mask" "F.Paste")
			(net "GND")
		)
		(pad "DB35" smd circle
			(at -2.970022 31.139892 180)
			(size 0.450088 0.450088)
			(layers "F.Cu" "F.Mask" "F.Paste")
			(net "P5E_CPU1_P3_RX_DP<2>")
		)
		(pad "DB36" smd circle
			(at -2.029968 31.139892 180)
			(size 0.450088 0.450088)
			(layers "F.Cu" "F.Mask" "F.Paste")
			(net "P5E_CPU1_P3_RX_DN<2>")
		)
		(pad "DB37" smd circle
			(at -1.089914 31.139892 180)
			(size 0.450088 0.450088)
			(layers "F.Cu" "F.Mask" "F.Paste")
			(net "GND")
		)
		(pad "DB39" smd circle
			(at 0.78994 31.139892 180)
			(size 0.450088 0.450088)
			(layers "F.Cu" "F.Mask" "F.Paste")
			(net "GND")
		)
		(pad "DB40" smd circle
			(at 1.729994 31.139892 180)
			(size 0.450088 0.450088)
			(layers "F.Cu" "F.Mask" "F.Paste")
			(net "P5E_CPU1_P1_TX_DN<13>")
		)
		(pad "DB41" smd circle
			(at 2.670048 31.139892 180)
			(size 0.450088 0.450088)
			(layers "F.Cu" "F.Mask" "F.Paste")
			(net "P5E_CPU1_P1_TX_DP<13>")
		)
		(pad "DB42" smd circle
			(at 3.610102 31.139892 180)
			(size 0.450088 0.450088)
			(layers "F.Cu" "F.Mask" "F.Paste")
			(net "GND")
		)
		(pad "DB43" smd circle
			(at 4.549902 31.139892 180)
			(size 0.450088 0.450088)
			(layers "F.Cu" "F.Mask" "F.Paste")
			(net "PVDDCR_CPU1_P1")
		)
		(pad "DB44" smd circle
			(at 5.489956 31.139892 180)
			(size 0.450088 0.450088)
			(layers "F.Cu" "F.Mask" "F.Paste")
			(net "PVDDCR_CPU1_P1")
		)
		(pad "DB45" smd circle
			(at 6.43001 31.139892 180)
			(size 0.450088 0.450088)
			(layers "F.Cu" "F.Mask" "F.Paste")
			(net "GND")
		)
		(pad "DB46" smd circle
			(at 7.370064 31.139892 180)
			(size 0.450088 0.450088)
			(layers "F.Cu" "F.Mask" "F.Paste")
			(net "PVDDCR_CPU1_P1")
		)
		(pad "DB47" smd circle
			(at 8.310118 31.139892 180)
			(size 0.450088 0.450088)
			(layers "F.Cu" "F.Mask" "F.Paste")
			(net "PVDDCR_CPU1_P1")
		)
		(pad "DB48" smd circle
			(at 9.249918 31.139892 180)
			(size 0.450088 0.450088)
			(layers "F.Cu" "F.Mask" "F.Paste")
			(net "GND")
		)
		(pad "DB49" smd circle
			(at 10.189972 31.139892 180)
			(size 0.450088 0.450088)
			(layers "F.Cu" "F.Mask" "F.Paste")
			(net "PVDDCR_CPU1_P1")
		)
		(pad "DB50" smd circle
			(at 11.130026 31.139892 180)
			(size 0.450088 0.450088)
			(layers "F.Cu" "F.Mask" "F.Paste")
			(net "PVDDCR_CPU1_P1")
		)
		(pad "DB51" smd circle
			(at 12.07008 31.139892 180)
			(size 0.450088 0.450088)
			(layers "F.Cu" "F.Mask" "F.Paste")
			(net "GND")
		)
		(pad "DB52" smd circle
			(at 13.00988 31.139892 180)
			(size 0.450088 0.450088)
			(layers "F.Cu" "F.Mask" "F.Paste")
			(net "PVDDCR_CPU1_P1")
		)
		(pad "DB53" smd circle
			(at 13.949934 31.139892 180)
			(size 0.450088 0.450088)
			(layers "F.Cu" "F.Mask" "F.Paste")
			(net "PVDDCR_CPU1_P1")
		)
		(pad "DB54" smd circle
			(at 14.889988 31.139892 180)
			(size 0.450088 0.450088)
			(layers "F.Cu" "F.Mask" "F.Paste")
			(net "GND")
		)
		(pad "DB55" smd circle
			(at 15.830042 31.139892 180)
			(size 0.450088 0.450088)
			(layers "F.Cu" "F.Mask" "F.Paste")
			(net "M_C_CPU1_SB_DQ<27>")
		)
		(pad "DB56" smd circle
			(at 16.770096 31.139892 180)
			(size 0.450088 0.450088)
			(layers "F.Cu" "F.Mask" "F.Paste")
			(net "M_C_CPU1_SB_DQS_DP<3>")
		)
		(pad "DB57" smd circle
			(at 17.709896 31.139892 180)
			(size 0.450088 0.450088)
			(layers "F.Cu" "F.Mask" "F.Paste")
			(net "PVDDIO_P1")
		)
		(pad "DB58" smd circle
			(at 18.64995 31.139892 180)
			(size 0.450088 0.450088)
			(layers "F.Cu" "F.Mask" "F.Paste")
			(net "M_D_CPU1_SB_DQ<27>")
		)
		(pad "DB59" smd circle
			(at 19.590004 31.139892 180)
			(size 0.450088 0.450088)
			(layers "F.Cu" "F.Mask" "F.Paste")
			(net "GND")
		)
		(pad "DB60" smd circle
			(at 20.530058 31.139892 180)
			(size 0.450088 0.450088)
			(layers "F.Cu" "F.Mask" "F.Paste")
			(net "M_D_CPU1_SB_DQS_DP<3>")
		)
		(pad "DB61" smd circle
			(at 21.470112 31.139892 180)
			(size 0.450088 0.450088)
			(layers "F.Cu" "F.Mask" "F.Paste")
			(net "GND")
		)
	)
)
